# BASEBOARD_FAB2 (Tioga Pass) — schematic netlist excerpt (pin names and nets, part order shuffled) for the footprints in the layout excerpt that follows; sources: Cadence DE-HDL packaged netlist, KiCad conversion of Wiwynn_Tioga_Pass_MB.brd

C1C7  CAP_A  1.0UF 6.3V 10% X6S  pkg 0402V  page 206 : A = VR_PVCCIN_CPU1_VDD ; B = GND
C9F13  CAP  22UF 4V 20% X6S  pkg 0805LF  page 239 : A = P1V2_AUX_BMC ; B = GND
R9A18  RES  4.75K 1% CHIP  pkg 0402  page 119 : A = P3V3_STBY ; B = FM_PWR_LED

(kicad_pcb
	(version 20260206)
	(generator "pcbnew")
	(generator_version "10.0")
	(general
		(thickness 1.6)
		(legacy_teardrops no)
	)
	(paper "A4")
	(title_block
		(title "Wiwynn_Tioga_Pass_MB.brd")
		(comment 1 "Tioga Pass / footprints 562-564 of 4770")
	)
	(layers
		(0 "F.Cu" signal "TOP")
		(4 "In1.Cu" signal "L2GND")
		(6 "In2.Cu" signal "L3")
		(8 "In3.Cu" signal "L4GND")
		(10 "In4.Cu" signal "L5")
		(12 "In5.Cu" signal "L6GND")
		(14 "In6.Cu" signal "L7VCC")
		(16 "In7.Cu" signal "L8VCC")
		(18 "In8.Cu" signal "L9GND")
		(20 "In9.Cu" signal "L10")
		(22 "In10.Cu" signal "L11GND")
		(24 "In11.Cu" signal "L12")
		(26 "In12.Cu" signal "L13GND")
		(2 "B.Cu" signal "BOTTOM")
		(9 "F.Adhes" user "F.Adhesive")
		(11 "B.Adhes" user "B.Adhesive")
		(13 "F.Paste" user "Package Geometry/Pastemask Top")
		(15 "B.Paste" user "Package Geometry/Pastemask Bottom")
		(5 "F.SilkS" user "Ref Des/Silkscreen Top")
		(7 "B.SilkS" user "Ref Des/Silkscreen Bottom")
		(1 "F.Mask" user "Board Geometry/Soldermask Top")
		(3 "B.Mask" user "Board Geometry/Soldermask Bottom")
		(17 "Dwgs.User" user "User.Drawings")
		(19 "Cmts.User" user "User.Comments")
		(21 "Eco1.User" user "User.Eco1")
		(23 "Eco2.User" user "User.Eco2")
		(25 "Edge.Cuts" user "Board Geometry/Outline")
		(27 "Margin" user)
		(31 "F.CrtYd" user "Package Geometry/Place Bound Top")
		(29 "B.CrtYd" user "Package Geometry/Place Bound Bottom")
		(35 "F.Fab" user "Ref Des/Assembly Top")
		(33 "B.Fab" user "Ref Des/Assembly Bottom")
	)
	(footprint ""
		(layer "F.Cu")
		(at 472.7575 -139.573 90)
		(property "Reference" "R9A18"
			(at 0 0 90)
			(layer "F.SilkS")
			(hide yes)
			(effects
				(font
					(size 1.27 1.27)
				)
			)
		)
		(property "Value" ""
			(at 0 0 90)
			(layer "F.Fab")
			(effects
				(font
					(size 1.27 1.27)
				)
			)
		)
		(duplicate_pad_numbers_are_jumpers no)
		(fp_poly
			(pts
				(xy -0.2794 -0.1016) (xy 0.2794 -0.1016) (xy 0.2794 0.9906) (xy -0.2794 0.9906)
			)
			(stroke
				(width 0)
				(type default)
			)
			(fill no)
			(layer "F.CrtYd")
		)
		(fp_line
			(start 0.2794 -0.1016)
			(end -0.2794 -0.1016)
			(stroke
				(width 0.1)
				(type default)
			)
			(layer "F.Fab")
		)
		(fp_line
			(start -0.2794 -0.1016)
			(end -0.2794 0.9906)
			(stroke
				(width 0.1)
				(type default)
			)
			(layer "F.Fab")
		)
		(fp_line
			(start 0.2794 0.9906)
			(end 0.2794 -0.1016)
			(stroke
				(width 0.1)
				(type default)
			)
			(layer "F.Fab")
		)
		(fp_line
			(start -0.2794 0.9906)
			(end 0.2794 0.9906)
			(stroke
				(width 0.1)
				(type default)
			)
			(layer "F.Fab")
		)
		(pad "1" smd rect
			(at 0 0 90)
			(size 0.508 0.508)
			(layers "F.Cu" "F.Mask" "F.Paste")
			(net "P3V3_STBY")
		)
		(pad "2" smd rect
			(at 0 0.889 90)
			(size 0.508 0.508)
			(layers "F.Cu" "F.Mask" "F.Paste")
			(net "FM_PWR_LED")
		)
		(zone
			(layer "F.Cu")
			(hatch none 0.5)
			(connect_pads
				(clearance 0)
			)
			(min_thickness 0.25)
			(keepout
				(tracks allowed)
				(vias not_allowed)
				(pads allowed)
				(copperpour not_allowed)
				(footprints allowed)
			)
			(placement
				(enabled no)
				(sheetname "")
			)
			(fill
				(thermal_gap 0.5)
				(thermal_bridge_width 0.5)
				(island_removal_mode 0)
			)
			(polygon
				(pts
					(xy 473.0115 -139.319) (xy 473.0115 -139.827) (xy 473.3925 -139.827) (xy 473.3925 -139.319)
				)
			)
		)
		(zone
			(layer "F.Cu")
			(hatch none 0.5)
			(connect_pads
				(clearance 0)
			)
			(min_thickness 0.25)
			(keepout
				(tracks not_allowed)
				(vias allowed)
				(pads allowed)
				(copperpour not_allowed)
				(footprints allowed)
			)
			(placement
				(enabled no)
				(sheetname "")
			)
			(fill
				(thermal_gap 0.5)
				(thermal_bridge_width 0.5)
				(island_removal_mode 0)
			)
			(polygon
				(pts
					(xy 473.3925 -139.319) (xy 473.3925 -139.827) (xy 473.0115 -139.827) (xy 473.0115 -139.319)
				)
			)
		)
	)
	(footprint ""
		(layer "F.Cu")
		(at 16.1036 -98.7044 -90)
		(property "Reference" "C1C7"
			(at 0 0 270)
			(layer "F.SilkS")
			(hide yes)
			(effects
				(font
					(size 1.27 1.27)
				)
			)
		)
		(property "Value" ""
			(at 0 0 270)
			(layer "F.Fab")
			(effects
				(font
					(size 1.27 1.27)
				)
			)
		)
		(duplicate_pad_numbers_are_jumpers no)
		(fp_poly
			(pts
				(xy 0.3048 -0.1016) (xy 0.3048 0.9906) (xy -0.3048 0.9906) (xy -0.3048 -0.1016)
			)
			(stroke
				(width 0)
				(type default)
			)
			(fill no)
			(layer "F.CrtYd")
		)
		(fp_line
			(start -0.3048 0.9906)
			(end 0.3048 0.9906)
			(stroke
				(width 0.1)
				(type default)
			)
			(layer "F.Fab")
		)
		(fp_line
			(start 0.3048 0.9906)
			(end 0.3048 -0.1016)
			(stroke
				(width 0.1)
				(type default)
			)
			(layer "F.Fab")
		)
		(fp_line
			(start -0.3048 -0.1016)
			(end -0.3048 0.9906)
			(stroke
				(width 0.1)
				(type default)
			)
			(layer "F.Fab")
		)
		(fp_line
			(start 0.3048 -0.1016)
			(end -0.3048 -0.1016)
			(stroke
				(width 0.1)
				(type default)
			)
			(layer "F.Fab")
		)
		(pad "1" smd rect
			(at 0 0 270)
			(size 0.508 0.508)
			(layers "F.Cu" "F.Mask" "F.Paste")
			(net "VR_PVCCIN_CPU1_VDD")
		)
		(pad "2" smd rect
			(at 0 0.889 270)
			(size 0.508 0.508)
			(layers "F.Cu" "F.Mask" "F.Paste")
			(net "GND")
		)
		(zone
			(layer "F.Cu")
			(hatch none 0.5)
			(connect_pads
				(clearance 0)
			)
			(min_thickness 0.25)
			(keepout
				(tracks not_allowed)
				(vias allowed)
				(pads allowed)
				(copperpour not_allowed)
				(footprints allowed)
			)
			(placement
				(enabled no)
				(sheetname "")
			)
			(fill
				(thermal_gap 0.5)
				(thermal_bridge_width 0.5)
				(island_removal_mode 0)
			)
			(polygon
				(pts
					(xy 15.4686 -98.9584) (xy 15.4686 -98.4504) (xy 15.8496 -98.4504) (xy 15.8496 -98.9584)
				)
			)
		)
		(zone
			(layer "F.Cu")
			(hatch none 0.5)
			(connect_pads
				(clearance 0)
			)
			(min_thickness 0.25)
			(keepout
				(tracks allowed)
				(vias not_allowed)
				(pads allowed)
				(copperpour not_allowed)
				(footprints allowed)
			)
			(placement
				(enabled no)
				(sheetname "")
			)
			(fill
				(thermal_gap 0.5)
				(thermal_bridge_width 0.5)
				(island_removal_mode 0)
			)
			(polygon
				(pts
					(xy 15.8496 -98.9584) (xy 15.8496 -98.4504) (xy 15.4686 -98.4504) (xy 15.4686 -98.9584)
				)
			)
		)
	)
	(footprint ""
		(layer "F.Cu")
		(at 468.493602 -36.626292 -90)
		(property "Reference" "C9F13"
			(at 0 0 270)
			(layer "F.SilkS")
			(hide yes)
			(effects
				(font
					(size 1.27 1.27)
				)
			)
		)
		(property "Value" ""
			(at 0 0 270)
			(layer "F.Fab")
			(effects
				(font
					(size 1.27 1.27)
				)
			)
		)
		(duplicate_pad_numbers_are_jumpers no)
		(fp_poly
			(pts
				(xy -0.7239 -0.2159) (xy 0.7239 -0.2159) (xy 0.7239 1.9939) (xy -0.7239 1.9939)
			)
			(stroke
				(width 0)
				(type default)
			)
			(fill no)
			(layer "F.CrtYd")
		)
		(fp_line
			(start -0.7239 1.9939)
			(end 0.7239 1.9939)
			(stroke
				(width 0.1)
				(type default)
			)
			(layer "F.Fab")
		)
		(fp_line
			(start 0.7239 1.9939)
			(end 0.7239 -0.2159)
			(stroke
				(width 0.1)
				(type default)
			)
			(layer "F.Fab")
		)
		(fp_line
			(start -0.7239 -0.2159)
			(end -0.7239 1.9939)
			(stroke
				(width 0.1)
				(type default)
			)
			(layer "F.Fab")
		)
		(fp_line
			(start 0.7239 -0.2159)
			(end -0.7239 -0.2159)
			(stroke
				(width 0.1)
				(type default)
			)
			(layer "F.Fab")
		)
		(pad "1" smd rect
			(at 0 0 270)
			(size 1.27 1.016)
			(layers "F.Cu" "F.Mask" "F.Paste")
			(net "P1V2_AUX_BMC")
		)
		(pad "2" smd rect
			(at 0 1.778 270)
			(size 1.27 1.016)
			(layers "F.Cu" "F.Mask" "F.Paste")
			(net "GND")
		)
		(zone
			(layer "F.Cu")
			(hatch none 0.5)
			(connect_pads
				(clearance 0)
			)
			(min_thickness 0.25)
			(keepout
				(tracks not_allowed)
				(vias allowed)
				(pads allowed)
				(copperpour not_allowed)
				(footprints allowed)
			)
			(placement
				(enabled no)
				(sheetname "")
			)
			(fill
				(thermal_gap 0.5)
				(thermal_bridge_width 0.5)
				(island_removal_mode 0)
			)
			(polygon
				(pts
					(xy 467.985602 -37.261292) (xy 467.985602 -35.991292) (xy 467.223602 -35.991292) (xy 467.223602 -37.261292)
				)
			)
		)
	)
)
